(kicad_pcb
	(version 20241229)
	(generator "pcbnew")
	(generator_version "9.0")
	(general
		(thickness 1.63)
		(legacy_teardrops no)
	)
	(paper "A4")
	(title_block
		(title "CM4 Baseboard")
		(date "2026-01-05")
		(rev "1.1.1")
		(company "Antmicro Ltd")
		(comment 1 "www.antmicro.com")
		(comment 9 "footprints 325-329 of 506")
	)
	(layers
		(0 "F.Cu" signal)
		(4 "In1.Cu" power)
		(6 "In2.Cu" power)
		(8 "In3.Cu" signal)
		(10 "In4.Cu" signal)
		(2 "B.Cu" signal)
		(9 "F.Adhes" user "F.Adhesive")
		(11 "B.Adhes" user "B.Adhesive")
		(13 "F.Paste" user)
		(15 "B.Paste" user)
		(5 "F.SilkS" user "F.Silkscreen")
		(7 "B.SilkS" user "B.Silkscreen")
		(1 "F.Mask" user)
		(3 "B.Mask" user)
		(17 "Dwgs.User" user "User.Drawings")
		(19 "Cmts.User" user "User.Comments")
		(21 "Eco1.User" user "User.Eco1")
		(23 "Eco2.User" user "User.Eco2")
		(25 "Edge.Cuts" user)
		(27 "Margin" user)
		(31 "F.CrtYd" user "F.Courtyard")
		(29 "B.CrtYd" user "B.Courtyard")
		(35 "F.Fab" user)
		(33 "B.Fab" user)
	)
	(footprint "antmicro-footprints:C_0402_1005Metric"
		(layer "B.Cu")
		(at 119.117962 134.2665 90)
		(descr "Capacitor SMD 0402")
		(tags "capacitor SMD 0402")
		(property "Reference" "C502"
			(at -3.57 0.45 90)
			(layer "B.SilkS")
			(effects
				(font
					(size 0.7 0.7)
					(thickness 0.15)
				)
				(justify right bottom mirror)
			)
		)
		(property "Value" "C_1u_0402"
			(at -1.022927 -2.155213 90)
			(layer "B.Fab")
			(effects
				(font
					(size 0.7 0.7)
					(thickness 0.15)
				)
				(justify right bottom mirror)
			)
		)
		(property "Datasheet" "https://product.tdk.com/en/search/capacitor/ceramic/mlcc/info?part_no=C1005X6S1A105K050BC"
			(at 0 0 90)
			(layer "B.Fab")
			(hide yes)
			(effects
				(font
					(size 1.27 1.27)
					(thickness 0.15)
				)
			)
		)
		(property "Manufacturer" "TDK"
			(at 0 0 90)
			(unlocked yes)
			(layer "B.Fab")
			(hide yes)
			(effects
				(font
					(size 1 1)
					(thickness 0.15)
				)
				(justify mirror)
			)
		)
		(property "MPN" "C1005X6S1A105K050BC"
			(at 0 0 90)
			(unlocked yes)
			(layer "B.Fab")
			(hide yes)
			(effects
				(font
					(size 1 1)
					(thickness 0.15)
				)
				(justify mirror)
			)
		)
		(property "Val" "1u"
			(at 0 0 90)
			(unlocked yes)
			(layer "B.Fab")
			(hide yes)
			(effects
				(font
					(size 1 1)
					(thickness 0.15)
				)
				(justify mirror)
			)
		)
		(property "License" "Apache-2.0"
			(at 0 0 90)
			(unlocked yes)
			(layer "B.Fab")
			(hide yes)
			(effects
				(font
					(size 1 1)
					(thickness 0.15)
				)
				(justify mirror)
			)
		)
		(property "Author" "Antmicro"
			(at 0 0 90)
			(unlocked yes)
			(layer "B.Fab")
			(hide yes)
			(effects
				(font
					(size 1 1)
					(thickness 0.15)
				)
				(justify mirror)
			)
		)
		(property "Voltage" ""
			(at 0 0 90)
			(unlocked yes)
			(layer "B.Fab")
			(hide yes)
			(effects
				(font
					(size 1 1)
					(thickness 0.15)
				)
				(justify mirror)
			)
		)
		(property "Dielectric" ""
			(at 0 0 90)
			(unlocked yes)
			(layer "B.Fab")
			(hide yes)
			(effects
				(font
					(size 1 1)
					(thickness 0.15)
				)
				(justify mirror)
			)
		)
		(sheetname "/NVMe & microSD/")
		(sheetfile "nvme-micro-sd.kicad_sch")
		(attr smd)
		(fp_rect
			(start -0.925 0.47)
			(end 0.925 -0.47)
			(stroke
				(width 0.05)
				(type default)
			)
			(fill no)
			(layer "B.CrtYd")
		)
		(fp_line
			(start 0.504 -0.248)
			(end -0.494 -0.248)
			(stroke
				(width 0.15)
				(type solid)
			)
			(layer "B.Fab")
		)
		(fp_line
			(start -0.494 -0.248)
			(end -0.494 0.25)
			(stroke
				(width 0.15)
				(type solid)
			)
			(layer "B.Fab")
		)
		(fp_line
			(start 0.504 0.25)
			(end 0.504 -0.248)
			(stroke
				(width 0.15)
				(type solid)
			)
			(layer "B.Fab")
		)
		(fp_line
			(start -0.494 0.25)
			(end 0.504 0.25)
			(stroke
				(width 0.15)
				(type solid)
			)
			(layer "B.Fab")
		)
		(fp_text user "${REFERENCE}"
			(at -0.939 -4.599 270)
			(layer "B.Fab")
			(effects
				(font
					(size 0.7 0.7)
					(thickness 0.15)
				)
				(justify left bottom mirror)
			)
		)
		(fp_text user "License: Apache-2.0"
			(at -0.939 -5.799 270)
			(layer "B.Fab")
			(effects
				(font
					(size 0.7 0.7)
					(thickness 0.15)
				)
				(justify left bottom mirror)
			)
		)
		(fp_text user "Author: Antmicro"
			(at -0.939 -3.399 270)
			(layer "B.Fab")
			(effects
				(font
					(size 0.7 0.7)
					(thickness 0.15)
				)
				(justify left bottom mirror)
			)
		)
		(pad "1" smd roundrect
			(at -0.48 0 90)
			(size 0.59 0.64)
			(layers "B.Cu" "B.Mask" "B.Paste")
			(roundrect_rratio 0.25)
			(net 3 "GND")
			(pintype "passive")
		)
		(pad "2" smd roundrect
			(at 0.48 0 90)
			(size 0.59 0.64)
			(layers "B.Cu" "B.Mask" "B.Paste")
			(roundrect_rratio 0.25)
			(net 65 "3V3_SSD")
			(pintype "passive")
		)
	)
	(footprint "antmicro-footprints:C_0805_2012Metric"
		(layer "B.Cu")
		(at 63.512962 166.0415 -90)
		(descr "Capacitor SMD 0805")
		(tags "capacitor SMD 0805")
		(property "Reference" "C306"
			(at -0.465 -1.795 90)
			(layer "B.SilkS")
			(effects
				(font
					(size 0.7 0.7)
					(thickness 0.15)
				)
				(justify left bottom mirror)
			)
		)
		(property "Value" "C_22u_25V_0805"
			(at -2.055717 -1.963152 90)
			(layer "B.Fab")
			(effects
				(font
					(size 0.7 0.7)
					(thickness 0.15)
				)
				(justify left bottom mirror)
			)
		)
		(property "Datasheet" "https://product.samsungsem.com/mlcc/CL21A226MAYNNN.do"
			(at 0 0 270)
			(layer "B.Fab")
			(hide yes)
			(effects
				(font
					(size 1.27 1.27)
					(thickness 0.15)
				)
			)
		)
		(property "Manufacturer" "Samsung Electro-Mechanics"
			(at 0 0 270)
			(unlocked yes)
			(layer "B.Fab")
			(hide yes)
			(effects
				(font
					(size 1 1)
					(thickness 0.15)
				)
				(justify mirror)
			)
		)
		(property "MPN" "CL21A226MAYNNNE"
			(at 0 0 270)
			(unlocked yes)
			(layer "B.Fab")
			(hide yes)
			(effects
				(font
					(size 1 1)
					(thickness 0.15)
				)
				(justify mirror)
			)
		)
		(property "Val" "22u"
			(at 0 0 270)
			(unlocked yes)
			(layer "B.Fab")
			(hide yes)
			(effects
				(font
					(size 1 1)
					(thickness 0.15)
				)
				(justify mirror)
			)
		)
		(property "License" "Apache-2.0"
			(at 0 0 270)
			(unlocked yes)
			(layer "B.Fab")
			(hide yes)
			(effects
				(font
					(size 1 1)
					(thickness 0.15)
				)
				(justify mirror)
			)
		)
		(property "Author" "Antmicro"
			(at 0 0 270)
			(unlocked yes)
			(layer "B.Fab")
			(hide yes)
			(effects
				(font
					(size 1 1)
					(thickness 0.15)
				)
				(justify mirror)
			)
		)
		(property "Voltage" "25V"
			(at 0 0 270)
			(unlocked yes)
			(layer "B.Fab")
			(hide yes)
			(effects
				(font
					(size 1 1)
					(thickness 0.15)
				)
				(justify mirror)
			)
		)
		(property "Dielectric" "X5R"
			(at 0 0 270)
			(unlocked yes)
			(layer "B.Fab")
			(hide yes)
			(effects
				(font
					(size 1 1)
					(thickness 0.15)
				)
				(justify mirror)
			)
		)
		(property "Public" "False"
			(at 0 0 270)
			(unlocked yes)
			(layer "B.Fab")
			(hide yes)
			(effects
				(font
					(size 1 1)
					(thickness 0.15)
				)
				(justify mirror)
			)
		)
		(sheetname "/Supply/")
		(sheetfile "supply.kicad_sch")
		(attr smd)
		(fp_line
			(start -0.3 0.7)
			(end 0.3 0.7)
			(stroke
				(width 0.15)
				(type solid)
			)
			(layer "B.SilkS")
		)
		(fp_line
			(start -0.3 -0.7)
			(end 0.3 -0.7)
			(stroke
				(width 0.15)
				(type solid)
			)
			(layer "B.SilkS")
		)
		(fp_rect
			(start 1.95 0.9)
			(end -1.95 -0.9)
			(stroke
				(width 0.05)
				(type default)
			)
			(fill no)
			(layer "B.CrtYd")
		)
		(fp_rect
			(start -0.95 0.675)
			(end 0.95 -0.675)
			(stroke
				(width 0.15)
				(type solid)
			)
			(fill no)
			(layer "B.Fab")
		)
		(fp_text user "License: Apache-2.0"
			(at -1.9 -4.947 90)
			(layer "B.Fab")
			(effects
				(font
					(size 0.7 0.7)
					(thickness 0.15)
				)
				(justify left bottom mirror)
			)
		)
		(fp_text user "Author: Antmicro"
			(at -1.9 -5.947 90)
			(layer "B.Fab")
			(effects
				(font
					(size 0.7 0.7)
					(thickness 0.15)
				)
				(justify left bottom mirror)
			)
		)
		(fp_text user "${REFERENCE}"
			(at -1.9 -3.947 90)
			(layer "B.Fab")
			(effects
				(font
					(size 0.7 0.7)
					(thickness 0.15)
				)
				(justify left bottom mirror)
			)
		)
		(pad "1" smd roundrect
			(at -1.1 0 270)
			(size 1.2 1.3)
			(layers "B.Cu" "B.Mask" "B.Paste")
			(roundrect_rratio 0.25)
			(net 43 "VCC")
			(pintype "passive")
		)
		(pad "2" smd roundrect
			(at 1.1 0 270)
			(size 1.2 1.3)
			(layers "B.Cu" "B.Mask" "B.Paste")
			(roundrect_rratio 0.25)
			(net 3 "GND")
			(pintype "passive")
		)
	)
	(footprint "antmicro-footprints:FB_0603_1608Metric"
		(layer "B.Cu")
		(at 101.167962 176.4965 180)
		(property "Reference" "FB702"
			(at -4.945 -0.295 0)
			(layer "B.SilkS")
			(effects
				(font
					(size 0.7 0.7)
					(thickness 0.15)
				)
				(justify left bottom mirror)
			)
		)
		(property "Value" "FB_220Z_2.2A_TDK-MPZ_0603"
			(at 0 -1.5 0)
			(layer "B.Fab")
			(effects
				(font
					(size 0.7 0.7)
					(thickness 0.15)
				)
				(justify left bottom mirror)
			)
		)
		(property "Datasheet" "https://product.tdk.com/info/en/catalog/datasheets/beads_commercial_power_mpz1608_en.pdf"
			(at 0 0 180)
			(layer "B.Fab")
			(hide yes)
			(effects
				(font
					(size 1.27 1.27)
					(thickness 0.15)
				)
			)
		)
		(property "MPN" "MPZ1608S221ATA00"
			(at 0 0 180)
			(unlocked yes)
			(layer "B.Fab")
			(hide yes)
			(effects
				(font
					(size 1 1)
					(thickness 0.15)
				)
				(justify mirror)
			)
		)
		(property "Manufacturer" "TDK"
			(at 0 0 180)
			(unlocked yes)
			(layer "B.Fab")
			(hide yes)
			(effects
				(font
					(size 1 1)
					(thickness 0.15)
				)
				(justify mirror)
			)
		)
		(property "Author" "Antmicro"
			(at 0 0 180)
			(unlocked yes)
			(layer "B.Fab")
			(hide yes)
			(effects
				(font
					(size 1 1)
					(thickness 0.15)
				)
				(justify mirror)
			)
		)
		(property "License" "Apache-2.0"
			(at 0 0 180)
			(unlocked yes)
			(layer "B.Fab")
			(hide yes)
			(effects
				(font
					(size 1 1)
					(thickness 0.15)
				)
				(justify mirror)
			)
		)
		(property "Val" "220Z/2.2A"
			(at 0 0 180)
			(unlocked yes)
			(layer "B.Fab")
			(hide yes)
			(effects
				(font
					(size 1 1)
					(thickness 0.15)
				)
				(justify mirror)
			)
		)
		(property "Current" ""
			(at 0 0 180)
			(unlocked yes)
			(layer "B.Fab")
			(hide yes)
			(effects
				(font
					(size 1 1)
					(thickness 0.15)
				)
				(justify mirror)
			)
		)
		(sheetname "/Display/")
		(sheetfile "display.kicad_sch")
		(attr smd)
		(fp_line
			(start -0.15 0.4)
			(end 0.15 0.4)
			(stroke
				(width 0.15)
				(type solid)
			)
			(layer "B.SilkS")
		)
		(fp_line
			(start -0.15 -0.4)
			(end 0.15 -0.4)
			(stroke
				(width 0.15)
				(type solid)
			)
			(layer "B.SilkS")
		)
		(fp_rect
			(start -1.25 0.65)
			(end 1.25 -0.65)
			(stroke
				(width 0.05)
				(type solid)
			)
			(fill no)
			(layer "B.CrtYd")
		)
		(fp_line
			(start 0.8 0.408)
			(end 0.8 -0.406)
			(stroke
				(width 0.15)
				(type solid)
			)
			(layer "B.Fab")
		)
		(fp_line
			(start 0.8 0.408)
			(end -0.803 0.408)
			(stroke
				(width 0.15)
				(type solid)
			)
			(layer "B.Fab")
		)
		(fp_line
			(start 0.8 -0.406)
			(end -0.803 -0.406)
			(stroke
				(width 0.15)
				(type solid)
			)
			(layer "B.Fab")
		)
		(fp_line
			(start -0.803 -0.406)
			(end -0.803 0.408)
			(stroke
				(width 0.15)
				(type solid)
			)
			(layer "B.Fab")
		)
		(fp_text user "License: Apache-2.0"
			(at -1.653 -5.9 0)
			(layer "B.Fab")
			(effects
				(font
					(size 0.7 0.7)
					(thickness 0.15)
				)
				(justify left bottom mirror)
			)
		)
		(fp_text user "${REFERENCE}"
			(at -1.653 -4.6 0)
			(layer "B.Fab")
			(effects
				(font
					(size 0.7 0.7)
					(thickness 0.15)
				)
				(justify left bottom mirror)
			)
		)
		(fp_text user "Author: Antmicro"
			(at -1.653 -3.162 0)
			(layer "B.Fab")
			(effects
				(font
					(size 0.7 0.7)
					(thickness 0.15)
				)
				(justify left bottom mirror)
			)
		)
		(pad "1" smd roundrect
			(at -0.7 0 180)
			(size 0.8 1)
			(layers "B.Cu" "B.Mask" "B.Paste")
			(roundrect_rratio 0.2)
			(net 10 "+5V")
			(pintype "passive")
		)
		(pad "2" smd roundrect
			(at 0.7 0 180)
			(size 0.8 1)
			(layers "B.Cu" "B.Mask" "B.Paste")
			(roundrect_rratio 0.2)
			(net 464 "Net-(D709-C)")
			(pintype "passive")
		)
	)
	(footprint "antmicro-footprints:SOD-523"
		(layer "B.Cu")
		(at 98.342962 176.8415 -90)
		(property "Reference" "D709"
			(at 0.065 -2.515 90)
			(layer "B.SilkS")
			(effects
				(font
					(size 0.7 0.7)
					(thickness 0.15)
				)
				(justify left bottom mirror)
			)
		)
		(property "Value" "PESD5Z5_0F"
			(at 0 -1.499 90)
			(layer "B.Fab")
			(effects
				(font
					(size 0.7 0.7)
					(thickness 0.15)
				)
				(justify left bottom mirror)
			)
		)
		(property "Datasheet" "https://assets.nexperia.com/documents/data-sheet/PESD5Z5_0.pdf"
			(at 0 0 270)
			(layer "B.Fab")
			(hide yes)
			(effects
				(font
					(size 1.27 1.27)
					(thickness 0.15)
				)
			)
		)
		(property "Manufacturer" "Nexperia"
			(at 0 0 270)
			(unlocked yes)
			(layer "B.Fab")
			(hide yes)
			(effects
				(font
					(size 1 1)
					(thickness 0.15)
				)
				(justify mirror)
			)
		)
		(property "MPN" "PESD5Z5.0F"
			(at 0 0 270)
			(unlocked yes)
			(layer "B.Fab")
			(hide yes)
			(effects
				(font
					(size 1 1)
					(thickness 0.15)
				)
				(justify mirror)
			)
		)
		(property "Author" "Antmicro"
			(at 0 0 270)
			(unlocked yes)
			(layer "B.Fab")
			(hide yes)
			(effects
				(font
					(size 1 1)
					(thickness 0.15)
				)
				(justify mirror)
			)
		)
		(property "License" "Apache-2.0"
			(at 0 0 270)
			(unlocked yes)
			(layer "B.Fab")
			(hide yes)
			(effects
				(font
					(size 1 1)
					(thickness 0.15)
				)
				(justify mirror)
			)
		)
		(sheetname "/Display/")
		(sheetfile "display.kicad_sch")
		(attr smd)
		(fp_line
			(start -0.35 0.5)
			(end -0.35 -0.5)
			(stroke
				(width 0.15)
				(type solid)
			)
			(layer "B.SilkS")
		)
		(fp_rect
			(start -1 0.6)
			(end 1 -0.6)
			(stroke
				(width 0.05)
				(type solid)
			)
			(fill no)
			(layer "B.CrtYd")
		)
		(fp_line
			(start -0.652 0.425)
			(end 0.65 0.425)
			(stroke
				(width 0.15)
				(type solid)
			)
			(layer "B.Fab")
		)
		(fp_line
			(start 0.65 0.425)
			(end 0.65 -0.423)
			(stroke
				(width 0.15)
				(type solid)
			)
			(layer "B.Fab")
		)
		(fp_line
			(start -0.35 0.4)
			(end -0.35 -0.4)
			(stroke
				(width 0.15)
				(type solid)
			)
			(layer "B.Fab")
		)
		(fp_line
			(start -0.652 -0.423)
			(end -0.652 0.425)
			(stroke
				(width 0.15)
				(type solid)
			)
			(layer "B.Fab")
		)
		(fp_line
			(start -0.652 -0.423)
			(end 0.65 -0.423)
			(stroke
				(width 0.15)
				(type solid)
			)
			(layer "B.Fab")
		)
		(fp_text user "${REFERENCE}"
			(at -1.276 -3.499 90)
			(layer "B.Fab")
			(effects
				(font
					(size 0.7 0.7)
					(thickness 0.15)
				)
				(justify left bottom mirror)
			)
		)
		(fp_text user "License: Apache-2.0"
			(at -1.276 -5.9 90)
			(layer "B.Fab")
			(effects
				(font
					(size 0.7 0.7)
					(thickness 0.15)
				)
				(justify left bottom mirror)
			)
		)
		(fp_text user "Author: Antmicro"
			(at -1.276 -4.7 90)
			(layer "B.Fab")
			(effects
				(font
					(size 0.7 0.7)
					(thickness 0.15)
				)
				(justify left bottom mirror)
			)
		)
		(pad "1" smd roundrect
			(at -0.701 0 270)
			(size 0.5 0.6)
			(layers "B.Cu" "B.Mask" "B.Paste")
			(roundrect_rratio 0.25)
			(net 464 "Net-(D709-C)")
			(pinfunction "C")
			(pintype "passive")
		)
		(pad "2" smd roundrect
			(at 0.699 0 270)
			(size 0.5 0.6)
			(layers "B.Cu" "B.Mask" "B.Paste")
			(roundrect_rratio 0.25)
			(net 3 "GND")
			(pinfunction "A")
			(pintype "passive")
		)
	)
	(footprint "antmicro-footprints:R_0402_1005Metric"
		(layer "B.Cu")
		(at 65.242962 175.2915 180)
		(descr "Resistor SMD 0402")
		(tags "resistor SMD 0402")
		(property "Reference" "R808"
			(at -1.507038 1.2915 0)
			(layer "B.SilkS")
			(effects
				(font
					(size 0.7 0.7)
					(thickness 0.15)
				)
				(justify left top mirror)
			)
		)
		(property "Value" "R_2k2_0402"
			(at -1.011843 -1.772046 0)
			(layer "B.Fab")
			(effects
				(font
					(size 0.7 0.7)
					(thickness 0.15)
				)
				(justify left top mirror)
			)
		)
		(property "Datasheet" "https://www.bourns.com/docs/product-datasheets/cr.pdf"
			(at 0 0 0)
			(layer "B.Fab")
			(hide yes)
			(effects
				(font
					(size 1.27 1.27)
					(thickness 0.15)
				)
			)
		)
		(property "Description" "SMD Chip Resistor, 2.2 kohm, ± 1%, 62.5 mW, 0402 [1005 Metric], Thick Film, General Purpose"
			(at 0 0 0)
			(layer "B.Fab")
			(hide yes)
			(effects
				(font
					(size 1.27 1.27)
					(thickness 0.15)
				)
			)
		)
		(property "MPN" "CR0402-FX-2201GLF"
			(at 0 0 180)
			(unlocked yes)
			(layer "B.Fab")
			(hide yes)
			(effects
				(font
					(size 1 1)
					(thickness 0.15)
				)
				(justify mirror)
			)
		)
		(property "Manufacturer" "Bourns"
			(at 0 0 180)
			(unlocked yes)
			(layer "B.Fab")
			(hide yes)
			(effects
				(font
					(size 1 1)
					(thickness 0.15)
				)
				(justify mirror)
			)
		)
		(property "License" "Apache-2.0"
			(at 0 0 180)
			(unlocked yes)
			(layer "B.Fab")
			(hide yes)
			(effects
				(font
					(size 1 1)
					(thickness 0.15)
				)
				(justify mirror)
			)
		)
		(property "Author" "Antmicro"
			(at 0 0 180)
			(unlocked yes)
			(layer "B.Fab")
			(hide yes)
			(effects
				(font
					(size 1 1)
					(thickness 0.15)
				)
				(justify mirror)
			)
		)
		(property "Val" "2k2"
			(at 0 0 180)
			(unlocked yes)
			(layer "B.Fab")
			(hide yes)
			(effects
				(font
					(size 1 1)
					(thickness 0.15)
				)
				(justify mirror)
			)
		)
		(property "Tolerance" "1%"
			(at 0 0 180)
			(unlocked yes)
			(layer "B.Fab")
			(hide yes)
			(effects
				(font
					(size 1 1)
					(thickness 0.15)
				)
				(justify mirror)
			)
		)
		(sheetname "/Peripherals/")
		(sheetfile "peripherals.kicad_sch")
		(attr smd)
		(fp_poly
			(pts
				(xy -0.925 0.47) (xy 0.925 0.47) (xy 0.925 -0.47) (xy -0.925 -0.47)
			)
			(stroke
				(width 0.05)
				(type default)
			)
			(fill no)
			(layer "B.CrtYd")
		)
		(fp_poly
			(pts
				(xy -0.5 0.25) (xy 0.5 0.25) (xy 0.5 -0.25) (xy -0.5 -0.25)
			)
			(stroke
				(width 0.15)
				(type solid)
			)
			(fill no)
			(layer "B.Fab")
		)
		(fp_text user "License: Apache-2.0"
			(at -0.949999 -5.169 0)
			(layer "B.Fab")
			(effects
				(font
					(size 0.7 0.7)
					(thickness 0.15)
				)
				(justify left bottom mirror)
			)
		)
		(fp_text user "${REFERENCE}"
			(at -0.95 -3.168 0)
			(layer "B.Fab")
			(effects
				(font
					(size 0.7 0.7)
					(thickness 0.15)
				)
				(justify left bottom mirror)
			)
		)
		(fp_text user "Author: Antmicro"
			(at -0.95 -4.169 0)
			(layer "B.Fab")
			(effects
				(font
					(size 0.7 0.7)
					(thickness 0.15)
				)
				(justify left bottom mirror)
			)
		)
		(pad "1" smd roundrect
			(at -0.48 0 180)
			(size 0.59 0.64)
			(layers "B.Cu" "B.Mask" "B.Paste")
			(roundrect_rratio 0.25)
			(net 104 "Net-(C813-Pad2)")
			(pintype "passive")
		)
		(pad "2" smd roundrect
			(at 0.48 0 180)
			(size 0.59 0.64)
			(layers "B.Cu" "B.Mask" "B.Paste")
			(roundrect_rratio 0.25)
			(net 110 "Net-(C817-Pad1)")
			(pintype "passive")
		)
	)
)
